# S9S_MB_2U (Grand Teton) — schematic netlist excerpt (pin names and nets, part order shuffled) for the footprints in the layout excerpt that follows; sources: Cadence DE-HDL packaged netlist, KiCad conversion of 03242023_DA0F0TMBIJ0_F0T_Motherboard_J_brd_V01_OCP.brd

R307  Q_RES  1K 1% CHIP  pkg 0402LF  page 284 : A = P3V3_AUX ; B = PWRGD_PVCCIN_CPU1_R
PC487  Q_CAP  100NF 50V 10% X7R  pkg C0402  page 288 : A = SW_PVCCIN_CPU1_BOOT8_R ; B = SW_PVCCIN_CPU1_BOOTR8

(kicad_pcb
	(version 20260206)
	(generator "pcbnew")
	(generator_version "10.0")
	(general
		(thickness 1.6)
		(legacy_teardrops no)
	)
	(paper "A4")
	(title_block
		(title "03242023_DA0F0TMBIJ0_F0T_Motherboard_J_brd_V01_OCP.brd")
		(comment 1 "Grand Teton / footprints 3815-3816 of 6105")
	)
	(layers
		(0 "F.Cu" signal "TOP")
		(4 "In1.Cu" signal "GND")
		(6 "In2.Cu" signal "IN1")
		(8 "In3.Cu" signal "GND1")
		(10 "In4.Cu" signal "IN2")
		(12 "In5.Cu" signal "GND2")
		(14 "In6.Cu" signal "IN3")
		(16 "In7.Cu" signal "GND3")
		(18 "In8.Cu" signal "VCC")
		(20 "In9.Cu" signal "VCC1")
		(22 "In10.Cu" signal "GND4")
		(24 "In11.Cu" signal "IN4")
		(26 "In12.Cu" signal "GND5")
		(28 "In13.Cu" signal "IN5")
		(30 "In14.Cu" signal "GND6")
		(32 "In15.Cu" signal "IN6")
		(34 "In16.Cu" signal "GND7")
		(2 "B.Cu" signal "BOTTOM")
		(9 "F.Adhes" user "F.Adhesive")
		(11 "B.Adhes" user "B.Adhesive")
		(13 "F.Paste" user "Package Geometry/Pastemask Top")
		(15 "B.Paste" user "Package Geometry/Pastemask Bottom")
		(5 "F.SilkS" user "Ref Des/Silkscreen Top")
		(7 "B.SilkS" user "Ref Des/Silkscreen Bottom")
		(1 "F.Mask" user "Board Geometry/Soldermask Top")
		(3 "B.Mask" user "Board Geometry/Soldermask Bottom")
		(17 "Dwgs.User" user "User.Drawings")
		(19 "Cmts.User" user "User.Comments")
		(21 "Eco1.User" user "User.Eco1")
		(23 "Eco2.User" user "User.Eco2")
		(25 "Edge.Cuts" user "Board Geometry/Outline")
		(27 "Margin" user)
		(31 "F.CrtYd" user "Package Geometry/Place Bound Top")
		(29 "B.CrtYd" user "Package Geometry/Place Bound Bottom")
		(35 "F.Fab" user "Ref Des/Assembly Top")
		(33 "B.Fab" user "Ref Des/Assembly Bottom")
	)
	(footprint ""
		(layer "F.Cu")
		(at 139.586208 -347.520514 -90)
		(property "Reference" "PC487"
			(at 0 0 270)
			(layer "F.SilkS")
			(hide yes)
			(effects
				(font
					(size 1.27 1.27)
				)
			)
		)
		(property "Value" ""
			(at 0 0 270)
			(layer "F.Fab")
			(effects
				(font
					(size 1.27 1.27)
				)
			)
		)
		(duplicate_pad_numbers_are_jumpers no)
		(fp_line
			(start -0.7874 0.4064)
			(end -0.7874 -0.4064)
			(stroke
				(width 0.1524)
				(type default)
			)
			(layer "F.SilkS")
		)
		(fp_line
			(start 0.7874 0.4064)
			(end -0.7874 0.4064)
			(stroke
				(width 0.1524)
				(type default)
			)
			(layer "F.SilkS")
		)
		(fp_line
			(start -0.7874 -0.4064)
			(end 0.7874 -0.4064)
			(stroke
				(width 0.1524)
				(type default)
			)
			(layer "F.SilkS")
		)
		(fp_line
			(start 0.7874 -0.4064)
			(end 0.7874 0.4064)
			(stroke
				(width 0.1524)
				(type default)
			)
			(layer "F.SilkS")
		)
		(fp_line
			(start -0.67945 0.3048)
			(end -0.67945 -0.305054)
			(stroke
				(width 0.1)
				(type default)
			)
			(layer "F.Fab")
		)
		(fp_line
			(start -0.12065 0.3048)
			(end -0.67945 0.3048)
			(stroke
				(width 0.1)
				(type default)
			)
			(layer "F.Fab")
		)
		(fp_line
			(start 0.120396 0.3048)
			(end 0.120396 0.2794)
			(stroke
				(width 0.1)
				(type default)
			)
			(layer "F.Fab")
		)
		(fp_line
			(start 0.67945 0.3048)
			(end 0.120396 0.3048)
			(stroke
				(width 0.1)
				(type default)
			)
			(layer "F.Fab")
		)
		(fp_line
			(start -0.12065 0.2794)
			(end -0.12065 0.3048)
			(stroke
				(width 0.1)
				(type default)
			)
			(layer "F.Fab")
		)
		(fp_line
			(start 0.120396 0.2794)
			(end -0.12065 0.2794)
			(stroke
				(width 0.1)
				(type default)
			)
			(layer "F.Fab")
		)
		(fp_line
			(start -0.12065 -0.2794)
			(end 0.12065 -0.2794)
			(stroke
				(width 0.1)
				(type default)
			)
			(layer "F.Fab")
		)
		(fp_line
			(start 0.12065 -0.2794)
			(end 0.12065 -0.3048)
			(stroke
				(width 0.1)
				(type default)
			)
			(layer "F.Fab")
		)
		(fp_line
			(start 0.12065 -0.3048)
			(end 0.67945 -0.3048)
			(stroke
				(width 0.1)
				(type default)
			)
			(layer "F.Fab")
		)
		(fp_line
			(start 0.67945 -0.3048)
			(end 0.67945 0.3048)
			(stroke
				(width 0.1)
				(type default)
			)
			(layer "F.Fab")
		)
		(fp_line
			(start -0.67945 -0.305054)
			(end -0.12065 -0.305054)
			(stroke
				(width 0.1)
				(type default)
			)
			(layer "F.Fab")
		)
		(fp_line
			(start -0.12065 -0.305054)
			(end -0.12065 -0.2794)
			(stroke
				(width 0.1)
				(type default)
			)
			(layer "F.Fab")
		)
		(pad "1" smd circle
			(at -0.40005 0 270)
			(size 0 0)
			(layers "F.Cu" "F.Mask" "F.Paste")
			(net "SW_PVCCIN_CPU1_BOOT8_R")
		)
		(pad "2" smd circle
			(at 0.40005 0 270)
			(size 0 0)
			(layers "F.Cu" "F.Mask" "F.Paste")
			(net "SW_PVCCIN_CPU1_BOOTR8")
		)
	)
	(footprint ""
		(layer "F.Cu")
		(at 102.39375 -360.934762 -90)
		(property "Reference" "R307"
			(at 0 0 270)
			(layer "F.SilkS")
			(hide yes)
			(effects
				(font
					(size 1.27 1.27)
				)
			)
		)
		(property "Value" ""
			(at 0 0 270)
			(layer "F.Fab")
			(effects
				(font
					(size 1.27 1.27)
				)
			)
		)
		(duplicate_pad_numbers_are_jumpers no)
		(fp_line
			(start -0.7874 0.4064)
			(end -0.7874 -0.4064)
			(stroke
				(width 0.1524)
				(type default)
			)
			(layer "F.SilkS")
		)
		(fp_line
			(start 0.7874 0.4064)
			(end -0.7874 0.4064)
			(stroke
				(width 0.1524)
				(type default)
			)
			(layer "F.SilkS")
		)
		(fp_line
			(start -0.7874 -0.4064)
			(end 0.7874 -0.4064)
			(stroke
				(width 0.1524)
				(type default)
			)
			(layer "F.SilkS")
		)
		(fp_line
			(start 0.7874 -0.4064)
			(end 0.7874 0.4064)
			(stroke
				(width 0.1524)
				(type default)
			)
			(layer "F.SilkS")
		)
		(fp_line
			(start -0.67945 0.3048)
			(end -0.67945 -0.305054)
			(stroke
				(width 0.1)
				(type default)
			)
			(layer "F.Fab")
		)
		(fp_line
			(start -0.12065 0.3048)
			(end -0.67945 0.3048)
			(stroke
				(width 0.1)
				(type default)
			)
			(layer "F.Fab")
		)
		(fp_line
			(start 0.120396 0.3048)
			(end 0.120396 0.2794)
			(stroke
				(width 0.1)
				(type default)
			)
			(layer "F.Fab")
		)
		(fp_line
			(start 0.67945 0.3048)
			(end 0.120396 0.3048)
			(stroke
				(width 0.1)
				(type default)
			)
			(layer "F.Fab")
		)
		(fp_line
			(start -0.12065 0.2794)
			(end -0.12065 0.3048)
			(stroke
				(width 0.1)
				(type default)
			)
			(layer "F.Fab")
		)
		(fp_line
			(start 0.120396 0.2794)
			(end -0.12065 0.2794)
			(stroke
				(width 0.1)
				(type default)
			)
			(layer "F.Fab")
		)
		(fp_line
			(start -0.12065 -0.2794)
			(end 0.12065 -0.2794)
			(stroke
				(width 0.1)
				(type default)
			)
			(layer "F.Fab")
		)
		(fp_line
			(start 0.12065 -0.2794)
			(end 0.12065 -0.3048)
			(stroke
				(width 0.1)
				(type default)
			)
			(layer "F.Fab")
		)
		(fp_line
			(start 0.12065 -0.3048)
			(end 0.67945 -0.3048)
			(stroke
				(width 0.1)
				(type default)
			)
			(layer "F.Fab")
		)
		(fp_line
			(start 0.67945 -0.3048)
			(end 0.67945 0.3048)
			(stroke
				(width 0.1)
				(type default)
			)
			(layer "F.Fab")
		)
		(fp_line
			(start -0.67945 -0.305054)
			(end -0.12065 -0.305054)
			(stroke
				(width 0.1)
				(type default)
			)
			(layer "F.Fab")
		)
		(fp_line
			(start -0.12065 -0.305054)
			(end -0.12065 -0.2794)
			(stroke
				(width 0.1)
				(type default)
			)
			(layer "F.Fab")
		)
		(pad "1" smd circle
			(at -0.40005 0 270)
			(size 0 0)
			(layers "F.Cu" "F.Mask" "F.Paste")
			(net "P3V3_AUX")
		)
		(pad "2" smd circle
			(at 0.40005 0 270)
			(size 0 0)
			(layers "F.Cu" "F.Mask" "F.Paste")
			(net "PWRGD_PVCCIN_CPU1_R")
		)
	)
)
